FILE_TYPE=LIBRARY_PARTS;
primitive 'OSC4_7X25000018';
  pin
    'OE':
      PIN_NUMBER='(1)';
      INPUT_LOAD='(-0.01,0.01)';
    'GND':
      PIN_NUMBER='(2)';
      PINUSE='POWER';
      NO_LOAD_CHECK='Both';
      NO_IO_CHECK='Both';
      NO_ASSERT_CHECK='TRUE';
      NO_DIR_CHECK='TRUE';
      ALLOW_CONNECT='TRUE';
    'OUT':
      PIN_NUMBER='(3)';
      OUTPUT_LOAD='(1.0,-1.0)';
    'VDD':
      PIN_NUMBER='(4)';
      PINUSE='POWER';
      NO_LOAD_CHECK='Both';
      NO_IO_CHECK='Both';
      NO_ASSERT_CHECK='TRUE';
      NO_DIR_CHECK='TRUE';
      ALLOW_CONNECT='TRUE';
  end_pin;
  body
    PART_NAME='OSC4_7X25000018';
    BODY_NAME='OSC4_7X25000018';
    PHYS_DES_PREFIX='OSC';
    CLASS='DISCRETE';
  end_body;
end_primitive;

END.
